# BASEBOARD_FAB2 (Tioga Pass) — schematic netlist excerpt (pin names and nets, part order shuffled) for the footprints in the layout excerpt that follows; sources: Cadence DE-HDL packaged netlist, KiCad conversion of Wiwynn_Tioga_Pass_MB.brd

R25W112  RES  4.75K 1% EMPTY  pkg 0402  page 150 : A = P3V3_STBY ; B = RMII_BMC_PCH_SPRNGVLLE_TXD0_R
R1T36  RES  0.0 5% CHIP  pkg 0402  page 93 : A = FM_CPU0_PROCHOT_LVT3_N ; B = FM_CPU0_PROCHOT_LVT3_BMC_N
R7B8  RES  10.0K 1% EMPTY  pkg 0402  page 116 : A = A_EXTCLKN ; B = GND

(kicad_pcb
	(version 20260206)
	(generator "pcbnew")
	(generator_version "10.0")
	(general
		(thickness 1.6)
		(legacy_teardrops no)
	)
	(paper "A4")
	(title_block
		(title "Wiwynn_Tioga_Pass_MB.brd")
		(comment 1 "Tioga Pass / footprints 2022-2024 of 4770")
	)
	(layers
		(0 "F.Cu" signal "TOP")
		(4 "In1.Cu" signal "L2GND")
		(6 "In2.Cu" signal "L3")
		(8 "In3.Cu" signal "L4GND")
		(10 "In4.Cu" signal "L5")
		(12 "In5.Cu" signal "L6GND")
		(14 "In6.Cu" signal "L7VCC")
		(16 "In7.Cu" signal "L8VCC")
		(18 "In8.Cu" signal "L9GND")
		(20 "In9.Cu" signal "L10")
		(22 "In10.Cu" signal "L11GND")
		(24 "In11.Cu" signal "L12")
		(26 "In12.Cu" signal "L13GND")
		(2 "B.Cu" signal "BOTTOM")
		(9 "F.Adhes" user "F.Adhesive")
		(11 "B.Adhes" user "B.Adhesive")
		(13 "F.Paste" user "Package Geometry/Pastemask Top")
		(15 "B.Paste" user "Package Geometry/Pastemask Bottom")
		(5 "F.SilkS" user "Ref Des/Silkscreen Top")
		(7 "B.SilkS" user "Ref Des/Silkscreen Bottom")
		(1 "F.Mask" user "Board Geometry/Soldermask Top")
		(3 "B.Mask" user "Board Geometry/Soldermask Bottom")
		(17 "Dwgs.User" user "User.Drawings")
		(19 "Cmts.User" user "User.Comments")
		(21 "Eco1.User" user "User.Eco1")
		(23 "Eco2.User" user "User.Eco2")
		(25 "Edge.Cuts" user "Board Geometry/Outline")
		(27 "Margin" user)
		(31 "F.CrtYd" user "Package Geometry/Place Bound Top")
		(29 "B.CrtYd" user "Package Geometry/Place Bound Bottom")
		(35 "F.Fab" user "Ref Des/Assembly Top")
		(33 "B.Fab" user "Ref Des/Assembly Bottom")
	)
	(footprint ""
		(layer "F.Cu")
		(at 404.495 -22.098 180)
		(property "Reference" "R25W112"
			(at -0.8382 -0.67818 180)
			(unlocked yes)
			(layer "F.SilkS")
			(effects
				(font
					(size 0.4064 0.254)
					(thickness 0.1524)
				)
				(justify left)
			)
		)
		(property "Value" ""
			(at 0 0 180)
			(layer "F.Fab")
			(effects
				(font
					(size 1.27 1.27)
				)
			)
		)
		(duplicate_pad_numbers_are_jumpers no)
		(fp_poly
			(pts
				(xy -0.2794 -0.1016) (xy 0.2794 -0.1016) (xy 0.2794 0.9906) (xy -0.2794 0.9906)
			)
			(stroke
				(width 0)
				(type default)
			)
			(fill no)
			(layer "F.CrtYd")
		)
		(fp_line
			(start 0.2794 0.9906)
			(end 0.2794 -0.1016)
			(stroke
				(width 0.1)
				(type default)
			)
			(layer "F.Fab")
		)
		(fp_line
			(start 0.2794 -0.1016)
			(end -0.2794 -0.1016)
			(stroke
				(width 0.1)
				(type default)
			)
			(layer "F.Fab")
		)
		(fp_line
			(start -0.2794 0.9906)
			(end 0.2794 0.9906)
			(stroke
				(width 0.1)
				(type default)
			)
			(layer "F.Fab")
		)
		(fp_line
			(start -0.2794 -0.1016)
			(end -0.2794 0.9906)
			(stroke
				(width 0.1)
				(type default)
			)
			(layer "F.Fab")
		)
		(pad "1" smd rect
			(at 0 0 180)
			(size 0.508 0.508)
			(layers "F.Cu" "F.Mask" "F.Paste")
			(net "P3V3_STBY")
		)
		(pad "2" smd rect
			(at 0 0.889 180)
			(size 0.508 0.508)
			(layers "F.Cu" "F.Mask" "F.Paste")
			(net "RMII_BMC_PCH_SPRNGVLLE_TXD0_R")
		)
		(zone
			(layer "F.Cu")
			(hatch none 0.5)
			(connect_pads
				(clearance 0)
			)
			(min_thickness 0.25)
			(keepout
				(tracks not_allowed)
				(vias allowed)
				(pads allowed)
				(copperpour not_allowed)
				(footprints allowed)
			)
			(placement
				(enabled no)
				(sheetname "")
			)
			(fill
				(thermal_gap 0.5)
				(thermal_bridge_width 0.5)
				(island_removal_mode 0)
			)
			(polygon
				(pts
					(xy 404.749 -22.733) (xy 404.241 -22.733) (xy 404.241 -22.352) (xy 404.749 -22.352)
				)
			)
		)
		(zone
			(layer "F.Cu")
			(hatch none 0.5)
			(connect_pads
				(clearance 0)
			)
			(min_thickness 0.25)
			(keepout
				(tracks allowed)
				(vias not_allowed)
				(pads allowed)
				(copperpour not_allowed)
				(footprints allowed)
			)
			(placement
				(enabled no)
				(sheetname "")
			)
			(fill
				(thermal_gap 0.5)
				(thermal_bridge_width 0.5)
				(island_removal_mode 0)
			)
			(polygon
				(pts
					(xy 404.749 -22.352) (xy 404.241 -22.352) (xy 404.241 -22.733) (xy 404.749 -22.733)
				)
			)
		)
	)
	(footprint ""
		(layer "F.Cu")
		(at 370.7384 -127.762 -90)
		(property "Reference" "R7B8"
			(at 0 0 270)
			(layer "F.SilkS")
			(hide yes)
			(effects
				(font
					(size 1.27 1.27)
				)
			)
		)
		(property "Value" ""
			(at 0 0 270)
			(layer "F.Fab")
			(effects
				(font
					(size 1.27 1.27)
				)
			)
		)
		(duplicate_pad_numbers_are_jumpers no)
		(fp_poly
			(pts
				(xy -0.2794 -0.1016) (xy 0.2794 -0.1016) (xy 0.2794 0.9906) (xy -0.2794 0.9906)
			)
			(stroke
				(width 0)
				(type default)
			)
			(fill no)
			(layer "F.CrtYd")
		)
		(fp_line
			(start -0.2794 0.9906)
			(end 0.2794 0.9906)
			(stroke
				(width 0.1)
				(type default)
			)
			(layer "F.Fab")
		)
		(fp_line
			(start 0.2794 0.9906)
			(end 0.2794 -0.1016)
			(stroke
				(width 0.1)
				(type default)
			)
			(layer "F.Fab")
		)
		(fp_line
			(start -0.2794 -0.1016)
			(end -0.2794 0.9906)
			(stroke
				(width 0.1)
				(type default)
			)
			(layer "F.Fab")
		)
		(fp_line
			(start 0.2794 -0.1016)
			(end -0.2794 -0.1016)
			(stroke
				(width 0.1)
				(type default)
			)
			(layer "F.Fab")
		)
		(pad "1" smd rect
			(at 0 0 270)
			(size 0.508 0.508)
			(layers "F.Cu" "F.Mask" "F.Paste")
			(net "A_EXTCLKN")
		)
		(pad "2" smd rect
			(at 0 0.889 270)
			(size 0.508 0.508)
			(layers "F.Cu" "F.Mask" "F.Paste")
			(net "GND")
		)
		(zone
			(layer "F.Cu")
			(hatch none 0.5)
			(connect_pads
				(clearance 0)
			)
			(min_thickness 0.25)
			(keepout
				(tracks not_allowed)
				(vias allowed)
				(pads allowed)
				(copperpour not_allowed)
				(footprints allowed)
			)
			(placement
				(enabled no)
				(sheetname "")
			)
			(fill
				(thermal_gap 0.5)
				(thermal_bridge_width 0.5)
				(island_removal_mode 0)
			)
			(polygon
				(pts
					(xy 370.1034 -128.016) (xy 370.1034 -127.508) (xy 370.4844 -127.508) (xy 370.4844 -128.016)
				)
			)
		)
		(zone
			(layer "F.Cu")
			(hatch none 0.5)
			(connect_pads
				(clearance 0)
			)
			(min_thickness 0.25)
			(keepout
				(tracks allowed)
				(vias not_allowed)
				(pads allowed)
				(copperpour not_allowed)
				(footprints allowed)
			)
			(placement
				(enabled no)
				(sheetname "")
			)
			(fill
				(thermal_gap 0.5)
				(thermal_bridge_width 0.5)
				(island_removal_mode 0)
			)
			(polygon
				(pts
					(xy 370.4844 -128.016) (xy 370.4844 -127.508) (xy 370.1034 -127.508) (xy 370.1034 -128.016)
				)
			)
		)
	)
	(footprint ""
		(layer "F.Cu")
		(at 402.615146 -42.935652 90)
		(property "Reference" "R1T36"
			(at 0 0 90)
			(layer "F.SilkS")
			(hide yes)
			(effects
				(font
					(size 1.27 1.27)
				)
			)
		)
		(property "Value" ""
			(at 0 0 90)
			(layer "F.Fab")
			(effects
				(font
					(size 1.27 1.27)
				)
			)
		)
		(duplicate_pad_numbers_are_jumpers no)
		(fp_poly
			(pts
				(xy -0.2794 -0.1016) (xy 0.2794 -0.1016) (xy 0.2794 0.9906) (xy -0.2794 0.9906)
			)
			(stroke
				(width 0)
				(type default)
			)
			(fill no)
			(layer "F.CrtYd")
		)
		(fp_line
			(start 0.2794 -0.1016)
			(end -0.2794 -0.1016)
			(stroke
				(width 0.1)
				(type default)
			)
			(layer "F.Fab")
		)
		(fp_line
			(start -0.2794 -0.1016)
			(end -0.2794 0.9906)
			(stroke
				(width 0.1)
				(type default)
			)
			(layer "F.Fab")
		)
		(fp_line
			(start 0.2794 0.9906)
			(end 0.2794 -0.1016)
			(stroke
				(width 0.1)
				(type default)
			)
			(layer "F.Fab")
		)
		(fp_line
			(start -0.2794 0.9906)
			(end 0.2794 0.9906)
			(stroke
				(width 0.1)
				(type default)
			)
			(layer "F.Fab")
		)
		(pad "1" smd rect
			(at 0 0 90)
			(size 0.508 0.508)
			(layers "F.Cu" "F.Mask" "F.Paste")
			(net "FM_CPU0_PROCHOT_LVT3_N")
		)
		(pad "2" smd rect
			(at 0 0.889 90)
			(size 0.508 0.508)
			(layers "F.Cu" "F.Mask" "F.Paste")
			(net "FM_CPU0_PROCHOT_LVT3_BMC_N")
		)
		(zone
			(layer "F.Cu")
			(hatch none 0.5)
			(connect_pads
				(clearance 0)
			)
			(min_thickness 0.25)
			(keepout
				(tracks allowed)
				(vias not_allowed)
				(pads allowed)
				(copperpour not_allowed)
				(footprints allowed)
			)
			(placement
				(enabled no)
				(sheetname "")
			)
			(fill
				(thermal_gap 0.5)
				(thermal_bridge_width 0.5)
				(island_removal_mode 0)
			)
			(polygon
				(pts
					(xy 402.869146 -42.681652) (xy 402.869146 -43.189652) (xy 403.250146 -43.189652) (xy 403.250146 -42.681652)
				)
			)
		)
		(zone
			(layer "F.Cu")
			(hatch none 0.5)
			(connect_pads
				(clearance 0)
			)
			(min_thickness 0.25)
			(keepout
				(tracks not_allowed)
				(vias allowed)
				(pads allowed)
				(copperpour not_allowed)
				(footprints allowed)
			)
			(placement
				(enabled no)
				(sheetname "")
			)
			(fill
				(thermal_gap 0.5)
				(thermal_bridge_width 0.5)
				(island_removal_mode 0)
			)
			(polygon
				(pts
					(xy 403.250146 -42.681652) (xy 403.250146 -43.189652) (xy 402.869146 -43.189652) (xy 402.869146 -42.681652)
				)
			)
		)
	)
)
